# BASEBOARD_FAB2 (Tioga Pass) — schematic netlist excerpt (pin names and nets, part order shuffled) for the footprints in the layout excerpt that follows; sources: Cadence DE-HDL packaged netlist, KiCad conversion of Wiwynn_Tioga_Pass_MB.brd

R7P30  RES  100.0 1% CHIP  pkg 0402  page 112 : A = PVCCIO_CPU0 ; B = XDP_CPU_MBP0_N
R6W8  RES  4.75K 1% EMPTY  pkg 0402  page 247 : A = PCA9555_A1 ; B = GND
C2N23  CAP  10UF 6.3V 20% X6S  pkg 0603  page 130 : A = P3V3_STBY ; B = GND

(kicad_pcb
	(version 20260206)
	(generator "pcbnew")
	(generator_version "10.0")
	(general
		(thickness 1.6)
		(legacy_teardrops no)
	)
	(paper "A4")
	(title_block
		(title "Wiwynn_Tioga_Pass_MB.brd")
		(comment 1 "Tioga Pass / footprints 4315-4317 of 4770")
	)
	(layers
		(0 "F.Cu" signal "TOP")
		(4 "In1.Cu" signal "L2GND")
		(6 "In2.Cu" signal "L3")
		(8 "In3.Cu" signal "L4GND")
		(10 "In4.Cu" signal "L5")
		(12 "In5.Cu" signal "L6GND")
		(14 "In6.Cu" signal "L7VCC")
		(16 "In7.Cu" signal "L8VCC")
		(18 "In8.Cu" signal "L9GND")
		(20 "In9.Cu" signal "L10")
		(22 "In10.Cu" signal "L11GND")
		(24 "In11.Cu" signal "L12")
		(26 "In12.Cu" signal "L13GND")
		(2 "B.Cu" signal "BOTTOM")
		(9 "F.Adhes" user "F.Adhesive")
		(11 "B.Adhes" user "B.Adhesive")
		(13 "F.Paste" user "Package Geometry/Pastemask Top")
		(15 "B.Paste" user "Package Geometry/Pastemask Bottom")
		(5 "F.SilkS" user "Ref Des/Silkscreen Top")
		(7 "B.SilkS" user "Ref Des/Silkscreen Bottom")
		(1 "F.Mask" user "Board Geometry/Soldermask Top")
		(3 "B.Mask" user "Board Geometry/Soldermask Bottom")
		(17 "Dwgs.User" user "User.Drawings")
		(19 "Cmts.User" user "User.Comments")
		(21 "Eco1.User" user "User.Eco1")
		(23 "Eco2.User" user "User.Eco2")
		(25 "Edge.Cuts" user "Board Geometry/Outline")
		(27 "Margin" user)
		(31 "F.CrtYd" user "Package Geometry/Place Bound Top")
		(29 "B.CrtYd" user "Package Geometry/Place Bound Bottom")
		(35 "F.Fab" user "Ref Des/Assembly Top")
		(33 "B.Fab" user "Ref Des/Assembly Bottom")
	)
	(footprint ""
		(layer "B.Cu")
		(at 162.463988 -71.982076 180)
		(property "Reference" "R7P30"
			(at 0 0 0)
			(layer "B.SilkS")
			(hide yes)
			(effects
				(font
					(size 1.27 1.27)
				)
				(justify mirror)
			)
		)
		(property "Value" ""
			(at 0 0 0)
			(layer "B.Fab")
			(effects
				(font
					(size 1.27 1.27)
				)
				(justify mirror)
			)
		)
		(duplicate_pad_numbers_are_jumpers no)
		(fp_poly
			(pts
				(xy 0.2794 -0.1016) (xy -0.2794 -0.1016) (xy -0.2794 0.9906) (xy 0.2794 0.9906)
			)
			(stroke
				(width 0)
				(type default)
			)
			(fill no)
			(layer "B.CrtYd")
		)
		(fp_line
			(start 0.2794 0.9906)
			(end -0.2794 0.9906)
			(stroke
				(width 0.1)
				(type default)
			)
			(layer "B.Fab")
		)
		(fp_line
			(start 0.2794 -0.1016)
			(end 0.2794 0.9906)
			(stroke
				(width 0.1)
				(type default)
			)
			(layer "B.Fab")
		)
		(fp_line
			(start -0.2794 0.9906)
			(end -0.2794 -0.1016)
			(stroke
				(width 0.1)
				(type default)
			)
			(layer "B.Fab")
		)
		(fp_line
			(start -0.2794 -0.1016)
			(end 0.2794 -0.1016)
			(stroke
				(width 0.1)
				(type default)
			)
			(layer "B.Fab")
		)
		(pad "1" smd rect
			(at 0 0)
			(size 0.508 0.508)
			(layers "B.Cu" "B.Mask" "B.Paste")
			(net "PVCCIO_CPU0")
		)
		(pad "2" smd rect
			(at 0 0.889)
			(size 0.508 0.508)
			(layers "B.Cu" "B.Mask" "B.Paste")
			(net "XDP_CPU_MBP0_N")
		)
		(zone
			(layer "B.Cu")
			(hatch none 0.5)
			(connect_pads
				(clearance 0)
			)
			(min_thickness 0.25)
			(keepout
				(tracks not_allowed)
				(vias allowed)
				(pads allowed)
				(copperpour not_allowed)
				(footprints allowed)
			)
			(placement
				(enabled no)
				(sheetname "")
			)
			(fill
				(thermal_gap 0.5)
				(thermal_bridge_width 0.5)
				(island_removal_mode 0)
			)
			(polygon
				(pts
					(xy 162.209988 -72.617076) (xy 162.717988 -72.617076) (xy 162.717988 -72.236076) (xy 162.209988 -72.236076)
				)
			)
		)
		(zone
			(layer "B.Cu")
			(hatch none 0.5)
			(connect_pads
				(clearance 0)
			)
			(min_thickness 0.25)
			(keepout
				(tracks allowed)
				(vias not_allowed)
				(pads allowed)
				(copperpour not_allowed)
				(footprints allowed)
			)
			(placement
				(enabled no)
				(sheetname "")
			)
			(fill
				(thermal_gap 0.5)
				(thermal_bridge_width 0.5)
				(island_removal_mode 0)
			)
			(polygon
				(pts
					(xy 162.209988 -72.236076) (xy 162.717988 -72.236076) (xy 162.717988 -72.617076) (xy 162.209988 -72.617076)
				)
			)
		)
	)
	(footprint ""
		(layer "B.Cu")
		(at 481.623116 -144.009872 90)
		(property "Reference" "R6W8"
			(at 0.8382 -0.67818 90)
			(unlocked yes)
			(layer "B.SilkS")
			(effects
				(font
					(size 0.4064 0.254)
					(thickness 0.1524)
				)
				(justify left mirror)
			)
		)
		(property "Value" ""
			(at 0 0 90)
			(layer "B.Fab")
			(effects
				(font
					(size 1.27 1.27)
				)
				(justify mirror)
			)
		)
		(duplicate_pad_numbers_are_jumpers no)
		(fp_poly
			(pts
				(xy 0.2794 -0.1016) (xy -0.2794 -0.1016) (xy -0.2794 0.9906) (xy 0.2794 0.9906)
			)
			(stroke
				(width 0)
				(type default)
			)
			(fill no)
			(layer "B.CrtYd")
		)
		(fp_line
			(start 0.2794 -0.1016)
			(end 0.2794 0.9906)
			(stroke
				(width 0.1)
				(type default)
			)
			(layer "B.Fab")
		)
		(fp_line
			(start -0.2794 -0.1016)
			(end 0.2794 -0.1016)
			(stroke
				(width 0.1)
				(type default)
			)
			(layer "B.Fab")
		)
		(fp_line
			(start 0.2794 0.9906)
			(end -0.2794 0.9906)
			(stroke
				(width 0.1)
				(type default)
			)
			(layer "B.Fab")
		)
		(fp_line
			(start -0.2794 0.9906)
			(end -0.2794 -0.1016)
			(stroke
				(width 0.1)
				(type default)
			)
			(layer "B.Fab")
		)
		(pad "1" smd rect
			(at 0 0 270)
			(size 0.508 0.508)
			(layers "B.Cu" "B.Mask" "B.Paste")
			(net "PCA9555_A1")
		)
		(pad "2" smd rect
			(at 0 0.889 270)
			(size 0.508 0.508)
			(layers "B.Cu" "B.Mask" "B.Paste")
			(net "GND")
		)
		(zone
			(layer "B.Cu")
			(hatch none 0.5)
			(connect_pads
				(clearance 0)
			)
			(min_thickness 0.25)
			(keepout
				(tracks allowed)
				(vias not_allowed)
				(pads allowed)
				(copperpour not_allowed)
				(footprints allowed)
			)
			(placement
				(enabled no)
				(sheetname "")
			)
			(fill
				(thermal_gap 0.5)
				(thermal_bridge_width 0.5)
				(island_removal_mode 0)
			)
			(polygon
				(pts
					(xy 481.877116 -144.263872) (xy 481.877116 -143.755872) (xy 482.258116 -143.755872) (xy 482.258116 -144.263872)
				)
			)
		)
		(zone
			(layer "B.Cu")
			(hatch none 0.5)
			(connect_pads
				(clearance 0)
			)
			(min_thickness 0.25)
			(keepout
				(tracks not_allowed)
				(vias allowed)
				(pads allowed)
				(copperpour not_allowed)
				(footprints allowed)
			)
			(placement
				(enabled no)
				(sheetname "")
			)
			(fill
				(thermal_gap 0.5)
				(thermal_bridge_width 0.5)
				(island_removal_mode 0)
			)
			(polygon
				(pts
					(xy 482.258116 -144.263872) (xy 482.258116 -143.755872) (xy 481.877116 -143.755872) (xy 481.877116 -144.263872)
				)
			)
		)
	)
	(footprint ""
		(layer "B.Cu")
		(at 407.416 -103.8225)
		(property "Reference" "C2N23"
			(at 0 0 0)
			(layer "B.SilkS")
			(hide yes)
			(effects
				(font
					(size 1.27 1.27)
				)
				(justify mirror)
			)
		)
		(property "Value" ""
			(at 0 0 0)
			(layer "B.Fab")
			(effects
				(font
					(size 1.27 1.27)
				)
				(justify mirror)
			)
		)
		(duplicate_pad_numbers_are_jumpers no)
		(fp_poly
			(pts
				(xy 0.4953 -0.2032) (xy -0.4953 -0.2032) (xy -0.4953 1.6002) (xy 0.4953 1.6002)
			)
			(stroke
				(width 0)
				(type default)
			)
			(fill no)
			(layer "B.CrtYd")
		)
		(fp_line
			(start -0.4953 -0.2032)
			(end -0.4953 1.6002)
			(stroke
				(width 0.1)
				(type default)
			)
			(layer "B.Fab")
		)
		(fp_line
			(start -0.4953 1.6002)
			(end 0.4953 1.6002)
			(stroke
				(width 0.1)
				(type default)
			)
			(layer "B.Fab")
		)
		(fp_line
			(start 0.4953 -0.2032)
			(end -0.4953 -0.2032)
			(stroke
				(width 0.1)
				(type default)
			)
			(layer "B.Fab")
		)
		(fp_line
			(start 0.4953 1.6002)
			(end 0.4953 -0.2032)
			(stroke
				(width 0.1)
				(type default)
			)
			(layer "B.Fab")
		)
		(pad "1" smd rect
			(at 0 0 180)
			(size 0.762 0.889)
			(layers "B.Cu" "B.Mask" "B.Paste")
			(net "P3V3_STBY")
		)
		(pad "2" smd rect
			(at 0 1.397 180)
			(size 0.762 0.889)
			(layers "B.Cu" "B.Mask" "B.Paste")
			(net "GND")
		)
		(zone
			(layer "B.Cu")
			(hatch none 0.5)
			(connect_pads
				(clearance 0)
			)
			(min_thickness 0.25)
			(keepout
				(tracks not_allowed)
				(vias allowed)
				(pads allowed)
				(copperpour not_allowed)
				(footprints allowed)
			)
			(placement
				(enabled no)
				(sheetname "")
			)
			(fill
				(thermal_gap 0.5)
				(thermal_bridge_width 0.5)
				(island_removal_mode 0)
			)
			(polygon
				(pts
					(xy 407.797 -103.378) (xy 407.035 -103.378) (xy 407.035 -102.87) (xy 407.797 -102.87)
				)
			)
		)
	)
)
